(kicad_pcb
	(version 20221018)
	(generator pcbnew)
	(general
    (thickness 1.62)
  )
	(paper "A4")
	(title_block
    (title "ECP5 - Datacenter Secure Control Module (DC-SCM)")
    (date "2024-07-01")
    (rev "1.2.1")
		(comment 9 "footprints 360-367 of 506")
	)
	(layers
    (0 "F.Cu" signal)
    (1 "In1.Cu" power)
    (2 "In2.Cu" signal)
    (3 "In3.Cu" power)
    (4 "In4.Cu" power)
    (5 "In5.Cu" signal)
    (6 "In6.Cu" power)
    (31 "B.Cu" signal)
    (32 "B.Adhes" user "B.Adhesive")
    (33 "F.Adhes" user "F.Adhesive")
    (34 "B.Paste" user)
    (35 "F.Paste" user)
    (36 "B.SilkS" user "B.Silkscreen")
    (37 "F.SilkS" user "F.Silkscreen")
    (38 "B.Mask" user)
    (39 "F.Mask" user)
    (40 "Dwgs.User" user "User.Drawings")
    (41 "Cmts.User" user "User.Comments")
    (42 "Eco1.User" user "User.Eco1")
    (43 "Eco2.User" user "User.Eco2")
    (44 "Edge.Cuts" user)
    (45 "Margin" user)
    (46 "B.CrtYd" user "B.Courtyard")
    (47 "F.CrtYd" user "F.Courtyard")
    (48 "B.Fab" user)
    (49 "F.Fab" user)
  )
	(footprint "antmicro-footprints:C_0402_1005Metric" (layer "B.Cu")
    (at 104.85 129.2)
    (descr "Capacitor SMD 0402")
    (tags "capacitor SMD 0402")
    (property "Author" "Antmicro")
    (property "Dielectric" "C0G")
    (property "License" "Apache-2.0")
    (property "MPN" "GRM1555C1H102JA01D")
    (property "Manufacturer" "Murata")
    (property "Public" "False")
    (property "Sheetfile" "fpga-power-supply.kicad_sch")
    (property "Sheetname" "FPGA power supply")
    (property "Val" "1n")
    (property "Voltage" "50V")
    (property "ki_description" "SMD Multilayer Ceramic Capacitor, 1000 pF, 50 V, 0402 [1005 Metric], ± 5%, C0G / NP0, GRM Series")
    (property "ki_keywords" "0402, SMT, CAPACITOR, PASSIVE, CERAMIC, MLCC")
    (attr smd)
    (fp_text reference "C180" (at 0.29 20.695) (layer "B.SilkS")
        (effects (font (size 0.7 0.7) (thickness 0.127)) (justify mirror))
    )
    (fp_text value "C_1n_0402" (at 0 -1.17) (layer "B.Fab")
        (effects (font (size 1 1) (thickness 0.15)) (justify mirror))
    )
    (fp_text user "License: Apache-2.0" (at -0.939 -5.799 180) (layer "B.Fab") hide
        (effects (font (size 0.7 0.7) (thickness 0.15)) (justify left bottom mirror))
    )
    (fp_text user "${REFERENCE}" (at 0 0) (layer "B.Fab")
        (effects (font (size 0.25 0.25) (thickness 0.04)) (justify mirror))
    )
    (fp_text user "Author: Antmicro" (at -0.939 -3.399 180) (layer "B.Fab") hide
        (effects (font (size 0.7 0.7) (thickness 0.15)) (justify left bottom mirror))
    )
    (fp_rect (start -0.925 0.47) (end 0.925 -0.47)
      (stroke (width 0.05) (type default)) (fill none) (layer "B.CrtYd"))
    (fp_line (start -0.494 -0.248) (end -0.494 0.25)
      (stroke (width 0.15) (type solid)) (layer "B.Fab"))
    (fp_line (start -0.494 0.25) (end 0.504 0.25)
      (stroke (width 0.15) (type solid)) (layer "B.Fab"))
    (fp_line (start 0.504 -0.248) (end -0.494 -0.248)
      (stroke (width 0.15) (type solid)) (layer "B.Fab"))
    (fp_line (start 0.504 0.25) (end 0.504 -0.248)
      (stroke (width 0.15) (type solid)) (layer "B.Fab"))
    (pad "1" smd roundrect (at -0.48 0) (size 0.59 0.64) (layers "B.Cu" "B.Paste" "B.Mask") (roundrect_rratio 0.25)
      (net 1 "GND") (pintype "passive"))
    (pad "2" smd roundrect (at 0.48 0) (size 0.59 0.64) (layers "B.Cu" "B.Paste" "B.Mask") (roundrect_rratio 0.25)
      (net 303 "/FPGA power supply/VCCA1") (pintype "passive"))
  )
	(footprint "antmicro-footprints:C_0402_1005Metric" (layer "B.Cu")
    (at 96.865 128.8)
    (descr "Capacitor SMD 0402")
    (tags "capacitor SMD 0402")
    (property "Author" "Antmicro")
    (property "Dielectric" "C0G")
    (property "License" "Apache-2.0")
    (property "MPN" "GRM1555C1H102JA01D")
    (property "Manufacturer" "Murata")
    (property "Public" "False")
    (property "Sheetfile" "fpga-power-supply.kicad_sch")
    (property "Sheetname" "FPGA power supply")
    (property "Val" "1n")
    (property "Voltage" "50V")
    (property "ki_description" "SMD Multilayer Ceramic Capacitor, 1000 pF, 50 V, 0402 [1005 Metric], ± 5%, C0G / NP0, GRM Series")
    (property "ki_keywords" "0402, SMT, CAPACITOR, PASSIVE, CERAMIC, MLCC")
    (attr smd)
    (fp_text reference "C153" (at -2.895 -0.185) (layer "B.SilkS")
        (effects (font (size 0.7 0.7) (thickness 0.127)) (justify mirror))
    )
    (fp_text value "C_1n_0402" (at 0 -1.17) (layer "B.Fab")
        (effects (font (size 1 1) (thickness 0.15)) (justify mirror))
    )
    (fp_text user "Author: Antmicro" (at -0.939 -3.399 180) (layer "B.Fab") hide
        (effects (font (size 0.7 0.7) (thickness 0.15)) (justify left bottom mirror))
    )
    (fp_text user "License: Apache-2.0" (at -0.939 -5.799 180) (layer "B.Fab") hide
        (effects (font (size 0.7 0.7) (thickness 0.15)) (justify left bottom mirror))
    )
    (fp_text user "${REFERENCE}" (at 0 0) (layer "B.Fab")
        (effects (font (size 0.25 0.25) (thickness 0.04)) (justify mirror))
    )
    (fp_rect (start -0.925 0.47) (end 0.925 -0.47)
      (stroke (width 0.05) (type default)) (fill none) (layer "B.CrtYd"))
    (fp_line (start -0.494 -0.248) (end -0.494 0.25)
      (stroke (width 0.15) (type solid)) (layer "B.Fab"))
    (fp_line (start -0.494 0.25) (end 0.504 0.25)
      (stroke (width 0.15) (type solid)) (layer "B.Fab"))
    (fp_line (start 0.504 -0.248) (end -0.494 -0.248)
      (stroke (width 0.15) (type solid)) (layer "B.Fab"))
    (fp_line (start 0.504 0.25) (end 0.504 -0.248)
      (stroke (width 0.15) (type solid)) (layer "B.Fab"))
    (pad "1" smd roundrect (at -0.48 0) (size 0.59 0.64) (layers "B.Cu" "B.Paste" "B.Mask") (roundrect_rratio 0.25)
      (net 1 "GND") (pintype "passive"))
    (pad "2" smd roundrect (at 0.48 0) (size 0.59 0.64) (layers "B.Cu" "B.Paste" "B.Mask") (roundrect_rratio 0.25)
      (net 302 "/FPGA power supply/VCCA0") (pintype "passive"))
  )
	(footprint "antmicro-footprints:C_0402_1005Metric" (layer "B.Cu")
    (at 101.925 132.25 90)
    (descr "Capacitor SMD 0402")
    (tags "capacitor SMD 0402")
    (property "Author" "Antmicro")
    (property "Dielectric" "")
    (property "License" "Apache-2.0")
    (property "MPN" "C1005X5R1E474M050BB")
    (property "Manufacturer" "TDK")
    (property "Public" "False")
    (property "Sheetfile" "fpga-power-supply.kicad_sch")
    (property "Sheetname" "FPGA power supply")
    (property "Val" "470n")
    (property "Voltage" "")
    (property "ki_description" "SMD Multilayer Ceramic Capacitor, 0.47 µF, 25 V, 0402 [1005 Metric], ± 20%, X5R, C")
    (property "ki_keywords" "0402, SMT, CAPACITOR, PASSIVE, CERAMIC, MLCC")
    (attr smd)
    (fp_text reference "C135" (at -20.705 0.975 90) (layer "B.SilkS")
        (effects (font (size 0.7 0.7) (thickness 0.127)) (justify mirror))
    )
    (fp_text value "C_470n_0402" (at 0 -1.17 90) (layer "B.Fab")
        (effects (font (size 1 1) (thickness 0.15)) (justify mirror))
    )
    (fp_text user "${REFERENCE}" (at 0 0 90) (layer "B.Fab")
        (effects (font (size 0.25 0.25) (thickness 0.04)) (justify mirror))
    )
    (fp_text user "License: Apache-2.0" (at -0.939 -5.799 270) (layer "B.Fab") hide
        (effects (font (size 0.7 0.7) (thickness 0.15)) (justify left bottom mirror))
    )
    (fp_text user "Author: Antmicro" (at -0.939 -3.399 270) (layer "B.Fab") hide
        (effects (font (size 0.7 0.7) (thickness 0.15)) (justify left bottom mirror))
    )
    (fp_rect (start -0.925 0.47) (end 0.925 -0.47)
      (stroke (width 0.05) (type default)) (fill none) (layer "B.CrtYd"))
    (fp_line (start -0.494 -0.248) (end -0.494 0.25)
      (stroke (width 0.15) (type solid)) (layer "B.Fab"))
    (fp_line (start -0.494 0.25) (end 0.504 0.25)
      (stroke (width 0.15) (type solid)) (layer "B.Fab"))
    (fp_line (start 0.504 -0.248) (end -0.494 -0.248)
      (stroke (width 0.15) (type solid)) (layer "B.Fab"))
    (fp_line (start 0.504 0.25) (end 0.504 -0.248)
      (stroke (width 0.15) (type solid)) (layer "B.Fab"))
    (pad "1" smd roundrect (at -0.48 0 90) (size 0.59 0.64) (layers "B.Cu" "B.Paste" "B.Mask") (roundrect_rratio 0.25)
      (net 1 "GND") (pintype "passive"))
    (pad "2" smd roundrect (at 0.48 0 90) (size 0.59 0.64) (layers "B.Cu" "B.Paste" "B.Mask") (roundrect_rratio 0.25)
      (net 302 "/FPGA power supply/VCCA0") (pintype "passive"))
  )
	(footprint "antmicro-footprints:C_0402_1005Metric" (layer "B.Cu")
    (at 105.15 117.05 -90)
    (descr "Capacitor SMD 0402")
    (tags "capacitor SMD 0402")
    (property "Author" "Antmicro")
    (property "Dielectric" "")
    (property "License" "Apache-2.0")
    (property "MPN" "C1005X5R1E474M050BB")
    (property "Manufacturer" "TDK")
    (property "Public" "False")
    (property "Sheetfile" "fpga-power-supply.kicad_sch")
    (property "Sheetname" "FPGA power supply")
    (property "Val" "470n")
    (property "Voltage" "")
    (property "ki_description" "SMD Multilayer Ceramic Capacitor, 0.47 µF, 25 V, 0402 [1005 Metric], ± 20%, X5R, C")
    (property "ki_keywords" "0402, SMT, CAPACITOR, PASSIVE, CERAMIC, MLCC")
    (attr smd)
    (fp_text reference "C195" (at 22.65 0.05 -90) (layer "B.SilkS")
        (effects (font (size 0.7 0.7) (thickness 0.127)) (justify mirror))
    )
    (fp_text value "C_470n_0402" (at 0 -1.17 -90) (layer "B.Fab")
        (effects (font (size 1 1) (thickness 0.15)) (justify mirror))
    )
    (fp_text user "License: Apache-2.0" (at -0.939 -5.799 90) (layer "B.Fab") hide
        (effects (font (size 0.7 0.7) (thickness 0.15)) (justify left bottom mirror))
    )
    (fp_text user "${REFERENCE}" (at 0 0 -90) (layer "B.Fab")
        (effects (font (size 0.25 0.25) (thickness 0.04)) (justify mirror))
    )
    (fp_text user "Author: Antmicro" (at -0.939 -3.399 90) (layer "B.Fab") hide
        (effects (font (size 0.7 0.7) (thickness 0.15)) (justify left bottom mirror))
    )
    (fp_rect (start -0.925 0.47) (end 0.925 -0.47)
      (stroke (width 0.05) (type default)) (fill none) (layer "B.CrtYd"))
    (fp_line (start -0.494 -0.248) (end -0.494 0.25)
      (stroke (width 0.15) (type solid)) (layer "B.Fab"))
    (fp_line (start -0.494 0.25) (end 0.504 0.25)
      (stroke (width 0.15) (type solid)) (layer "B.Fab"))
    (fp_line (start 0.504 -0.248) (end -0.494 -0.248)
      (stroke (width 0.15) (type solid)) (layer "B.Fab"))
    (fp_line (start 0.504 0.25) (end 0.504 -0.248)
      (stroke (width 0.15) (type solid)) (layer "B.Fab"))
    (pad "1" smd roundrect (at -0.48 0 270) (size 0.59 0.64) (layers "B.Cu" "B.Paste" "B.Mask") (roundrect_rratio 0.25)
      (net 211 "VCC1V2") (pintype "passive"))
    (pad "2" smd roundrect (at 0.48 0 270) (size 0.59 0.64) (layers "B.Cu" "B.Paste" "B.Mask") (roundrect_rratio 0.25)
      (net 1 "GND") (pintype "passive"))
  )
	(footprint "antmicro-footprints:C_0402_1005Metric" (layer "B.Cu")
    (at 108.95 94.6 180)
    (descr "Capacitor SMD 0402")
    (tags "capacitor SMD 0402")
    (property "Author" "Antmicro")
    (property "Dielectric" "")
    (property "License" "Apache-2.0")
    (property "MPN" "GRM155R61A475MEAAD")
    (property "Manufacturer" "Murata")
    (property "Public" "False")
    (property "Sheetfile" "ethernet.kicad_sch")
    (property "Sheetname" "Ethernet")
    (property "Val" "4u7")
    (property "Voltage" "")
    (property "ki_description" "SMD Multilayer Ceramic Capacitor, 4.7 µF, 10 V, 0402 [1005 Metric], ± 20%, X5R, GRM Series")
    (property "ki_keywords" "0402, SMT, CAPACITOR, PASSIVE")
    (attr smd)
    (fp_text reference "C22" (at 0.1 5.17) (layer "B.SilkS")
        (effects (font (size 0.7 0.7) (thickness 0.127)) (justify mirror))
    )
    (fp_text value "C_4u7_0402" (at 0 -1.17) (layer "B.Fab")
        (effects (font (size 1 1) (thickness 0.15)) (justify mirror))
    )
    (fp_text user "License: Apache-2.0" (at -0.939 -5.799) (layer "B.Fab") hide
        (effects (font (size 0.7 0.7) (thickness 0.15)) (justify left bottom mirror))
    )
    (fp_text user "Author: Antmicro" (at -0.939 -3.399) (layer "B.Fab") hide
        (effects (font (size 0.7 0.7) (thickness 0.15)) (justify left bottom mirror))
    )
    (fp_text user "${REFERENCE}" (at 0 0) (layer "B.Fab")
        (effects (font (size 0.25 0.25) (thickness 0.04)) (justify mirror))
    )
    (fp_rect (start -0.925 0.47) (end 0.925 -0.47)
      (stroke (width 0.05) (type default)) (fill none) (layer "B.CrtYd"))
    (fp_line (start -0.494 -0.248) (end -0.494 0.25)
      (stroke (width 0.15) (type solid)) (layer "B.Fab"))
    (fp_line (start -0.494 0.25) (end 0.504 0.25)
      (stroke (width 0.15) (type solid)) (layer "B.Fab"))
    (fp_line (start 0.504 -0.248) (end -0.494 -0.248)
      (stroke (width 0.15) (type solid)) (layer "B.Fab"))
    (fp_line (start 0.504 0.25) (end 0.504 -0.248)
      (stroke (width 0.15) (type solid)) (layer "B.Fab"))
    (pad "1" smd roundrect (at -0.48 0 180) (size 0.59 0.64) (layers "B.Cu" "B.Paste" "B.Mask") (roundrect_rratio 0.25)
      (net 1 "GND") (pintype "passive"))
    (pad "2" smd roundrect (at 0.48 0 180) (size 0.59 0.64) (layers "B.Cu" "B.Paste" "B.Mask") (roundrect_rratio 0.25)
      (net 10 "/Ethernet/AVDDL_PLL") (pintype "passive"))
  )
	(footprint "antmicro-footprints:C_0402_1005Metric" (layer "B.Cu")
    (at 104.4 93.35 90)
    (descr "Capacitor SMD 0402")
    (tags "capacitor SMD 0402")
    (property "Author" "Antmicro")
    (property "Dielectric" "X7R")
    (property "License" "Apache-2.0")
    (property "MPN" "GRM155R71H103KA88D")
    (property "Manufacturer" "Murata")
    (property "Public" "False")
    (property "Sheetfile" "ethernet.kicad_sch")
    (property "Sheetname" "Ethernet")
    (property "Val" "10n")
    (property "Voltage" "50V")
    (property "ki_description" "SMD Multilayer Ceramic Capacitor, 10000 pF, 50 V, 0402 [1005 Metric], ± 10%, X7R, GRM Series")
    (property "ki_keywords" "0402, SMT, CAPACITOR, PASSIVE")
    (attr smd)
    (fp_text reference "C21" (at -0.075 -0.86 90) (layer "B.SilkS")
        (effects (font (size 0.7 0.7) (thickness 0.127)) (justify mirror))
    )
    (fp_text value "C_10n_0402" (at 0 -1.17 90) (layer "B.Fab")
        (effects (font (size 1 1) (thickness 0.15)) (justify mirror))
    )
    (fp_text user "${REFERENCE}" (at 0 0 90) (layer "B.Fab")
        (effects (font (size 0.25 0.25) (thickness 0.04)) (justify mirror))
    )
    (fp_text user "Author: Antmicro" (at -0.939 -3.399 270) (layer "B.Fab") hide
        (effects (font (size 0.7 0.7) (thickness 0.15)) (justify left bottom mirror))
    )
    (fp_text user "License: Apache-2.0" (at -0.939 -5.799 270) (layer "B.Fab") hide
        (effects (font (size 0.7 0.7) (thickness 0.15)) (justify left bottom mirror))
    )
    (fp_rect (start -0.925 0.47) (end 0.925 -0.47)
      (stroke (width 0.05) (type default)) (fill none) (layer "B.CrtYd"))
    (fp_line (start -0.494 -0.248) (end -0.494 0.25)
      (stroke (width 0.15) (type solid)) (layer "B.Fab"))
    (fp_line (start -0.494 0.25) (end 0.504 0.25)
      (stroke (width 0.15) (type solid)) (layer "B.Fab"))
    (fp_line (start 0.504 -0.248) (end -0.494 -0.248)
      (stroke (width 0.15) (type solid)) (layer "B.Fab"))
    (fp_line (start 0.504 0.25) (end 0.504 -0.248)
      (stroke (width 0.15) (type solid)) (layer "B.Fab"))
    (pad "1" smd roundrect (at -0.48 0 90) (size 0.59 0.64) (layers "B.Cu" "B.Paste" "B.Mask") (roundrect_rratio 0.25)
      (net 1 "GND") (pintype "passive"))
    (pad "2" smd roundrect (at 0.48 0 90) (size 0.59 0.64) (layers "B.Cu" "B.Paste" "B.Mask") (roundrect_rratio 0.25)
      (net 9 "/Ethernet/AVDDL") (pintype "passive"))
  )
	(footprint "antmicro-footprints:C_0402_1005Metric" (layer "B.Cu")
    (at 101.95 93.35 90)
    (descr "Capacitor SMD 0402")
    (tags "capacitor SMD 0402")
    (property "Author" "Antmicro")
    (property "Dielectric" "")
    (property "License" "Apache-2.0")
    (property "MPN" "C1005X5R1E474M050BB")
    (property "Manufacturer" "TDK")
    (property "Public" "False")
    (property "Sheetfile" "ethernet.kicad_sch")
    (property "Sheetname" "Ethernet")
    (property "Val" "470n")
    (property "Voltage" "")
    (property "ki_description" "SMD Multilayer Ceramic Capacitor, 0.47 µF, 25 V, 0402 [1005 Metric], ± 20%, X5R, C")
    (property "ki_keywords" "0402, SMT, CAPACITOR, PASSIVE, CERAMIC, MLCC")
    (attr smd)
    (fp_text reference "C19" (at -1.865 -0.02 90) (layer "B.SilkS")
        (effects (font (size 0.7 0.7) (thickness 0.127)) (justify mirror))
    )
    (fp_text value "C_470n_0402" (at 0 -1.17 90) (layer "B.Fab")
        (effects (font (size 1 1) (thickness 0.15)) (justify mirror))
    )
    (fp_text user "Author: Antmicro" (at -0.939 -3.399 270) (layer "B.Fab") hide
        (effects (font (size 0.7 0.7) (thickness 0.15)) (justify left bottom mirror))
    )
    (fp_text user "License: Apache-2.0" (at -0.939 -5.799 270) (layer "B.Fab") hide
        (effects (font (size 0.7 0.7) (thickness 0.15)) (justify left bottom mirror))
    )
    (fp_text user "${REFERENCE}" (at 0 0 90) (layer "B.Fab")
        (effects (font (size 0.25 0.25) (thickness 0.04)) (justify mirror))
    )
    (fp_rect (start -0.925 0.47) (end 0.925 -0.47)
      (stroke (width 0.05) (type default)) (fill none) (layer "B.CrtYd"))
    (fp_line (start -0.494 -0.248) (end -0.494 0.25)
      (stroke (width 0.15) (type solid)) (layer "B.Fab"))
    (fp_line (start -0.494 0.25) (end 0.504 0.25)
      (stroke (width 0.15) (type solid)) (layer "B.Fab"))
    (fp_line (start 0.504 -0.248) (end -0.494 -0.248)
      (stroke (width 0.15) (type solid)) (layer "B.Fab"))
    (fp_line (start 0.504 0.25) (end 0.504 -0.248)
      (stroke (width 0.15) (type solid)) (layer "B.Fab"))
    (pad "1" smd roundrect (at -0.48 0 90) (size 0.59 0.64) (layers "B.Cu" "B.Paste" "B.Mask") (roundrect_rratio 0.25)
      (net 1 "GND") (pintype "passive"))
    (pad "2" smd roundrect (at 0.48 0 90) (size 0.59 0.64) (layers "B.Cu" "B.Paste" "B.Mask") (roundrect_rratio 0.25)
      (net 9 "/Ethernet/AVDDL") (pintype "passive"))
  )
	(footprint "antmicro-footprints:C_0402_1005Metric" (layer "B.Cu")
    (at 101.95 90.55 -90)
    (descr "Capacitor SMD 0402")
    (tags "capacitor SMD 0402")
    (property "Author" "Antmicro")
    (property "Dielectric" "")
    (property "License" "Apache-2.0")
    (property "MPN" "GRM155R61A475MEAAD")
    (property "Manufacturer" "Murata")
    (property "Public" "False")
    (property "Sheetfile" "ethernet.kicad_sch")
    (property "Sheetname" "Ethernet")
    (property "Val" "4u7")
    (property "Voltage" "")
    (property "ki_description" "SMD Multilayer Ceramic Capacitor, 4.7 µF, 10 V, 0402 [1005 Metric], ± 20%, X5R, GRM Series")
    (property "ki_keywords" "0402, SMT, CAPACITOR, PASSIVE")
    (attr smd)
    (fp_text reference "C18" (at -1.845 0.42 90) (layer "B.SilkS")
        (effects (font (size 0.7 0.7) (thickness 0.127)) (justify mirror))
    )
    (fp_text value "C_4u7_0402" (at 0 -1.17 90) (layer "B.Fab")
        (effects (font (size 1 1) (thickness 0.15)) (justify mirror))
    )
    (fp_text user "Author: Antmicro" (at -0.939 -3.399 90) (layer "B.Fab") hide
        (effects (font (size 0.7 0.7) (thickness 0.15)) (justify left bottom mirror))
    )
    (fp_text user "${REFERENCE}" (at 0 0 90) (layer "B.Fab")
        (effects (font (size 0.25 0.25) (thickness 0.04)) (justify mirror))
    )
    (fp_text user "License: Apache-2.0" (at -0.939 -5.799 90) (layer "B.Fab") hide
        (effects (font (size 0.7 0.7) (thickness 0.15)) (justify left bottom mirror))
    )
    (fp_rect (start -0.925 0.47) (end 0.925 -0.47)
      (stroke (width 0.05) (type default)) (fill none) (layer "B.CrtYd"))
    (fp_line (start -0.494 -0.248) (end -0.494 0.25)
      (stroke (width 0.15) (type solid)) (layer "B.Fab"))
    (fp_line (start -0.494 0.25) (end 0.504 0.25)
      (stroke (width 0.15) (type solid)) (layer "B.Fab"))
    (fp_line (start 0.504 -0.248) (end -0.494 -0.248)
      (stroke (width 0.15) (type solid)) (layer "B.Fab"))
    (fp_line (start 0.504 0.25) (end 0.504 -0.248)
      (stroke (width 0.15) (type solid)) (layer "B.Fab"))
    (pad "1" smd roundrect (at -0.48 0 270) (size 0.59 0.64) (layers "B.Cu" "B.Paste" "B.Mask") (roundrect_rratio 0.25)
      (net 1 "GND") (pintype "passive"))
    (pad "2" smd roundrect (at 0.48 0 270) (size 0.59 0.64) (layers "B.Cu" "B.Paste" "B.Mask") (roundrect_rratio 0.25)
      (net 9 "/Ethernet/AVDDL") (pintype "passive"))
  )
)
